(kicad_pcb
	(version 20260206)
	(generator "pcbnew")
	(generator_version "10.0")
	(general
		(thickness 1.6)
		(legacy_teardrops no)
	)
	(paper "A4")
	(title_block
		(title "Bryce Canyon_IOM_M2_16342-2_OCP.brd")
		(comment 1 "Bryce Canyon / footprint 69 of 1146 (U2), pads 114-227 of 456")
	)
	(layers
		(0 "F.Cu" signal "TOP")
		(4 "In1.Cu" signal "L2GND")
		(6 "In2.Cu" signal "L3")
		(8 "In3.Cu" signal "L4VCC")
		(10 "In4.Cu" signal "L5VCC")
		(12 "In5.Cu" signal "L6")
		(14 "In6.Cu" signal "L7GND")
		(2 "B.Cu" signal "BOTTOM")
		(9 "F.Adhes" user "F.Adhesive")
		(11 "B.Adhes" user "B.Adhesive")
		(13 "F.Paste" user "Package Geometry/Pastemask Top")
		(15 "B.Paste" user "Package Geometry/Pastemask Bottom")
		(5 "F.SilkS" user "Ref Des/Silkscreen Top")
		(7 "B.SilkS" user "Ref Des/Silkscreen Bottom")
		(1 "F.Mask" user "Board Geometry/Soldermask Top")
		(3 "B.Mask" user "Board Geometry/Soldermask Bottom")
		(17 "Dwgs.User" user "User.Drawings")
		(19 "Cmts.User" user "User.Comments")
		(21 "Eco1.User" user "User.Eco1")
		(23 "Eco2.User" user "User.Eco2")
		(25 "Edge.Cuts" user "Board Geometry/Outline")
		(27 "Margin" user)
		(31 "F.CrtYd" user "Package Geometry/Place Bound Top")
		(29 "B.CrtYd" user "Package Geometry/Place Bound Bottom")
		(35 "F.Fab" user "Ref Des/Assembly Top")
		(33 "B.Fab" user "Ref Des/Assembly Bottom")
	)
	(footprint ""
		(layer "F.Cu")
		(at 47.69993 -144.999964 -90)
		(property "Reference" "U2"
			(at 0 0 270)
			(layer "F.SilkS")
			(hide yes)
			(effects
				(font
					(size 1.27 1.27)
				)
			)
		)
		(property "Value" "AST2500A2-GP-GP-U"
			(at -17.0307 -8.584692 270)
			(unlocked yes)
			(layer "F.Fab")
			(hide yes)
			(effects
				(font
					(size 1.016 1.016)
					(thickness 0.1524)
				)
			)
		)
		(property "Device Type" "BGA456D19H58"
			(at -17.0307 -10.108692 270)
			(unlocked yes)
			(layer "F.Fab")
			(hide yes)
			(effects
				(font
					(size 1.016 1.016)
					(thickness 0.1524)
				)
			)
		)
		(duplicate_pad_numbers_are_jumpers no)
		(pad "D4" smd circle
			(at -5.999988 -5.999988 270)
			(size 0.3556 0.3556)
			(layers "F.Cu" "F.Mask" "F.Paste")
			(net "MAC2_TXD3")
		)
		(pad "D5" smd circle
			(at -5.199888 -5.999988 270)
			(size 0.3556 0.3556)
			(layers "F.Cu" "F.Mask" "F.Paste")
			(net "MAC2_TXD2")
		)
		(pad "D6" smd circle
			(at -4.400042 -5.999988 270)
			(size 0.3556 0.3556)
			(layers "F.Cu" "F.Mask" "F.Paste")
			(net "NCSI_RXD1")
		)
		(pad "D7" smd circle
			(at -3.599942 -5.999988 270)
			(size 0.3556 0.3556)
			(layers "F.Cu" "F.Mask" "F.Paste")
			(net "MAC1_TXD3")
		)
		(pad "D8" smd circle
			(at -2.800096 -5.999988 270)
			(size 0.3556 0.3556)
			(layers "F.Cu" "F.Mask" "F.Paste")
			(net "RMII_BMC_MDC_R")
		)
		(pad "D9" smd circle
			(at -1.999996 -5.999988 270)
			(size 0.3556 0.3556)
			(layers "F.Cu" "F.Mask" "F.Paste")
			(net "BMC_SMB11_DAT")
		)
		(pad "D10" smd circle
			(at -1.199896 -5.999988 270)
			(size 0.3556 0.3556)
			(layers "F.Cu" "F.Mask" "F.Paste")
			(net "BMC_SMB12_CLK")
		)
		(pad "D11" smd circle
			(at -0.40005 -5.999988 270)
			(size 0.3556 0.3556)
			(layers "F.Cu" "F.Mask" "F.Paste")
			(net "JTAG_BMC_TDO")
		)
		(pad "D12" smd circle
			(at 0.40005 -5.999988 270)
			(size 0.3556 0.3556)
			(layers "F.Cu" "F.Mask" "F.Paste")
			(net "JTAG_BMC_TDI")
		)
		(pad "D13" smd circle
			(at 1.199896 -5.999988 270)
			(size 0.3556 0.3556)
			(layers "F.Cu" "F.Mask" "F.Paste")
			(net "BMC_TO_EXP_RESET_OUT")
		)
		(pad "D14" smd circle
			(at 1.999996 -5.999988 270)
			(size 0.3556 0.3556)
			(layers "F.Cu" "F.Mask" "F.Paste")
			(net "USB_OCS_N1")
		)
		(pad "D15" smd circle
			(at 2.800096 -5.999988 270)
			(size 0.3556 0.3556)
			(layers "F.Cu" "F.Mask" "F.Paste")
			(net "Net_8")
		)
		(pad "D16" smd circle
			(at 3.599942 -5.999988 270)
			(size 0.3556 0.3556)
			(layers "F.Cu" "F.Mask" "F.Paste")
			(net "Net_7")
		)
		(pad "D17" smd circle
			(at 4.400042 -5.999988 270)
			(size 0.3556 0.3556)
			(layers "F.Cu" "F.Mask" "F.Paste")
			(net "LED_POSTCODE_2")
		)
		(pad "D18" smd circle
			(at 5.199888 -5.999988 270)
			(size 0.3556 0.3556)
			(layers "F.Cu" "F.Mask" "F.Paste")
			(net "LED_POSTCODE_7")
		)
		(pad "D19" smd circle
			(at 5.999988 -5.999988 270)
			(size 0.3556 0.3556)
			(layers "F.Cu" "F.Mask" "F.Paste")
			(net "TP_BMC_EXT1_LED_G")
		)
		(pad "D20" smd circle
			(at 6.800088 -5.999988 270)
			(size 0.3556 0.3556)
			(layers "F.Cu" "F.Mask" "F.Paste")
			(net "COMP_PWR_BTN_R_N")
		)
		(pad "D21" smd circle
			(at 7.599934 -5.999988 270)
			(size 0.3556 0.3556)
			(layers "F.Cu" "F.Mask" "F.Paste")
			(net "RSTBTN_OUT_N_R")
		)
		(pad "D22" smd circle
			(at 8.400034 -5.999988 270)
			(size 0.3556 0.3556)
			(layers "F.Cu" "F.Mask" "F.Paste")
			(net "TP_BMC0_LPC_LAD2")
		)
		(pad "E1" smd circle
			(at -8.400034 -5.199888 270)
			(size 0.3556 0.3556)
			(layers "F.Cu" "F.Mask" "F.Paste")
			(net "ADC_P1V8_STBY")
		)
		(pad "E2" smd circle
			(at -7.599934 -5.199888 270)
			(size 0.3556 0.3556)
			(layers "F.Cu" "F.Mask" "F.Paste")
			(net "ADC_P3V3_STBY")
		)
		(pad "E3" smd circle
			(at -6.800088 -5.199888 270)
			(size 0.3556 0.3556)
			(layers "F.Cu" "F.Mask" "F.Paste")
			(net "ADC_P1V2_STBY")
		)
		(pad "E4" smd circle
			(at -5.999988 -5.199888 270)
			(size 0.3556 0.3556)
			(layers "F.Cu" "F.Mask" "F.Paste")
			(net "P3V3_STBY")
		)
		(pad "E5" smd circle
			(at -5.199888 -5.199888 270)
			(size 0.3556 0.3556)
			(layers "F.Cu" "F.Mask" "F.Paste")
			(net "GND")
		)
		(pad "E6" smd circle
			(at -4.400042 -5.199888 270)
			(size 0.3556 0.3556)
			(layers "F.Cu" "F.Mask" "F.Paste")
			(net "BMC_RGMII_C2_C3_D1_D2_E6")
		)
		(pad "E7" smd circle
			(at -3.599942 -5.199888 270)
			(size 0.3556 0.3556)
			(layers "F.Cu" "F.Mask" "F.Paste")
			(net "MAC1_TXD2")
		)
		(pad "E8" smd circle
			(at -2.800096 -5.199888 270)
			(size 0.3556 0.3556)
			(layers "F.Cu" "F.Mask" "F.Paste")
			(net "GND")
		)
		(pad "E9" smd circle
			(at -1.999996 -5.199888 270)
			(size 0.3556 0.3556)
			(layers "F.Cu" "F.Mask" "F.Paste")
			(net "NCSI_TXEN")
		)
		(pad "E10" smd circle
			(at -1.199896 -5.199888 270)
			(size 0.3556 0.3556)
			(layers "F.Cu" "F.Mask" "F.Paste")
			(net "RMII_BMC_MDIO_R")
		)
		(pad "E11" smd circle
			(at -0.40005 -5.199888 270)
			(size 0.3556 0.3556)
			(layers "F.Cu" "F.Mask" "F.Paste")
			(net "JTAG_BMC_TRST_N")
		)
		(pad "E12" smd circle
			(at 0.40005 -5.199888 270)
			(size 0.3556 0.3556)
			(layers "F.Cu" "F.Mask" "F.Paste")
			(net "BMC_SMB12_DAT")
		)
		(pad "E13" smd circle
			(at 1.199896 -5.199888 270)
			(size 0.3556 0.3556)
			(layers "F.Cu" "F.Mask" "F.Paste")
			(net "SYS_PWR_LED")
		)
		(pad "E14" smd circle
			(at 1.999996 -5.199888 270)
			(size 0.3556 0.3556)
			(layers "F.Cu" "F.Mask" "F.Paste")
			(net "I2C_COMP_ALERT_N")
		)
		(pad "E15" smd circle
			(at 2.800096 -5.199888 270)
			(size 0.3556 0.3556)
			(layers "F.Cu" "F.Mask" "F.Paste")
			(net "TP_BMC_GPIOI1")
		)
		(pad "E16" smd circle
			(at 3.599942 -5.199888 270)
			(size 0.3556 0.3556)
			(layers "F.Cu" "F.Mask" "F.Paste")
			(net "COMP_SPARE_1_R")
		)
		(pad "E17" smd circle
			(at 4.400042 -5.199888 270)
			(size 0.3556 0.3556)
			(layers "F.Cu" "F.Mask" "F.Paste")
			(net "SYS_RST_EN")
		)
		(pad "E18" smd circle
			(at 5.199888 -5.199888 270)
			(size 0.3556 0.3556)
			(layers "F.Cu" "F.Mask" "F.Paste")
			(net "TP_BMC_EXT1_LED_B")
		)
		(pad "E19" smd circle
			(at 5.999988 -5.199888 270)
			(size 0.3556 0.3556)
			(layers "F.Cu" "F.Mask" "F.Paste")
			(net "SLOTID_1")
		)
		(pad "E20" smd circle
			(at 6.800088 -5.199888 270)
			(size 0.3556 0.3556)
			(layers "F.Cu" "F.Mask" "F.Paste")
			(net "SYS_RESET_N_OUT_R")
		)
		(pad "E21" smd circle
			(at 7.599934 -5.199888 270)
			(size 0.3556 0.3556)
			(layers "F.Cu" "F.Mask" "F.Paste")
			(net "Net_547")
		)
		(pad "E22" smd circle
			(at 8.400034 -5.199888 270)
			(size 0.3556 0.3556)
			(layers "F.Cu" "F.Mask" "F.Paste")
			(net "TP_BMC0_LPC_LAD3")
		)
		(pad "F1" smd circle
			(at -8.400034 -4.400042 270)
			(size 0.3556 0.3556)
			(layers "F.Cu" "F.Mask" "F.Paste")
			(net "ADC_P3V3_M2")
		)
		(pad "F2" smd circle
			(at -7.599934 -4.400042 270)
			(size 0.3556 0.3556)
			(layers "F.Cu" "F.Mask" "F.Paste")
			(net "ADC_P1V8")
		)
		(pad "F3" smd circle
			(at -6.800088 -4.400042 270)
			(size 0.3556 0.3556)
			(layers "F.Cu" "F.Mask" "F.Paste")
			(net "ADC_P2V5_STBY")
		)
		(pad "F4" smd circle
			(at -5.999988 -4.400042 270)
			(size 0.3556 0.3556)
			(layers "F.Cu" "F.Mask" "F.Paste")
			(net "ADC_12V")
		)
		(pad "F5" smd circle
			(at -5.199888 -4.400042 270)
			(size 0.3556 0.3556)
			(layers "F.Cu" "F.Mask" "F.Paste")
			(net "ADC_P5V_STBY")
		)
		(pad "F6" smd circle
			(at -4.400042 -4.400042 270)
			(size 0.3556 0.3556)
			(layers "F.Cu" "F.Mask" "F.Paste")
			(net "P1V15_STBY")
		)
		(pad "F7" smd circle
			(at -3.599942 -4.400042 270)
			(size 0.3556 0.3556)
			(layers "F.Cu" "F.Mask" "F.Paste")
			(net "P3V3_STBY")
		)
		(pad "F8" smd circle
			(at -2.800096 -4.400042 270)
			(size 0.3556 0.3556)
			(layers "F.Cu" "F.Mask" "F.Paste")
			(net "P3V3_STBY")
		)
		(pad "F9" smd circle
			(at -1.999996 -4.400042 270)
			(size 0.3556 0.3556)
			(layers "F.Cu" "F.Mask" "F.Paste")
			(net "NCSI_TXD0_R")
		)
		(pad "F10" smd circle
			(at -1.199896 -4.400042 270)
			(size 0.3556 0.3556)
			(layers "F.Cu" "F.Mask" "F.Paste")
			(net "P3V3_STBY")
		)
		(pad "F11" smd circle
			(at -0.40005 -4.400042 270)
			(size 0.3556 0.3556)
			(layers "F.Cu" "F.Mask" "F.Paste")
			(net "P3V3_STBY")
		)
		(pad "F12" smd circle
			(at 0.40005 -4.400042 270)
			(size 0.3556 0.3556)
			(layers "F.Cu" "F.Mask" "F.Paste")
			(net "P3V3_STBY")
		)
		(pad "F13" smd circle
			(at 1.199896 -4.400042 270)
			(size 0.3556 0.3556)
			(layers "F.Cu" "F.Mask" "F.Paste")
			(net "P3V3_STBY")
		)
		(pad "F14" smd circle
			(at 1.999996 -4.400042 270)
			(size 0.3556 0.3556)
			(layers "F.Cu" "F.Mask" "F.Paste")
			(net "P3V3_STBY")
		)
		(pad "F15" smd circle
			(at 2.800096 -4.400042 270)
			(size 0.3556 0.3556)
			(layers "F.Cu" "F.Mask" "F.Paste")
			(net "P3V3_STBY")
		)
		(pad "F16" smd circle
			(at 3.599942 -4.400042 270)
			(size 0.3556 0.3556)
			(layers "F.Cu" "F.Mask" "F.Paste")
			(net "GND")
		)
		(pad "F17" smd circle
			(at 4.400042 -4.400042 270)
			(size 0.3556 0.3556)
			(layers "F.Cu" "F.Mask" "F.Paste")
			(net "M2_2_ACTIVE_N")
		)
		(pad "F18" smd circle
			(at 5.199888 -4.400042 270)
			(size 0.3556 0.3556)
			(layers "F.Cu" "F.Mask" "F.Paste")
			(net "M2_1_ACTIVE_N")
		)
		(pad "F19" smd circle
			(at 5.999988 -4.400042 270)
			(size 0.3556 0.3556)
			(layers "F.Cu" "F.Mask" "F.Paste")
			(net "Net_546")
		)
		(pad "F20" smd circle
			(at 6.800088 -4.400042 270)
			(size 0.3556 0.3556)
			(layers "F.Cu" "F.Mask" "F.Paste")
			(net "PWRBTN_OUT_N_R")
		)
		(pad "F21" smd circle
			(at 7.599934 -4.400042 270)
			(size 0.3556 0.3556)
			(layers "F.Cu" "F.Mask" "F.Paste")
			(net "LPC_CPU_FRAME_N")
		)
		(pad "F22" smd circle
			(at 8.400034 -4.400042 270)
			(size 0.3556 0.3556)
			(layers "F.Cu" "F.Mask" "F.Paste")
			(net "IRQ_CPU_SERIAL")
		)
		(pad "G1" smd circle
			(at -8.400034 -3.599942 270)
			(size 0.3556 0.3556)
			(layers "F.Cu" "F.Mask" "F.Paste")
			(net "GND")
		)
		(pad "G2" smd circle
			(at -7.599934 -3.599942 270)
			(size 0.3556 0.3556)
			(layers "F.Cu" "F.Mask" "F.Paste")
			(net "ADC_P0V975")
		)
		(pad "G3" smd circle
			(at -6.800088 -3.599942 270)
			(size 0.3556 0.3556)
			(layers "F.Cu" "F.Mask" "F.Paste")
			(net "ADC_P1V5")
		)
		(pad "G4" smd circle
			(at -5.999988 -3.599942 270)
			(size 0.3556 0.3556)
			(layers "F.Cu" "F.Mask" "F.Paste")
			(net "ADC_P3V3")
		)
		(pad "G5" smd circle
			(at -5.199888 -3.599942 270)
			(size 0.3556 0.3556)
			(layers "F.Cu" "F.Mask" "F.Paste")
			(net "ADC_P1V15_STBY")
		)
		(pad "G6" smd circle
			(at -4.400042 -3.599942 270)
			(size 0.3556 0.3556)
			(layers "F.Cu" "F.Mask" "F.Paste")
			(net "GND")
		)
		(pad "G7" smd circle
			(at -3.599942 -3.599942 270)
			(size 0.3556 0.3556)
			(layers "F.Cu" "F.Mask" "F.Paste")
			(net "P1V15_STBY")
		)
		(pad "G8" smd circle
			(at -2.800096 -3.599942 270)
			(size 0.3556 0.3556)
			(layers "F.Cu" "F.Mask" "F.Paste")
			(net "P1V15_STBY")
		)
		(pad "G9" smd circle
			(at -1.999996 -3.599942 270)
			(size 0.3556 0.3556)
			(layers "F.Cu" "F.Mask" "F.Paste")
			(net "P1V15_STBY")
		)
		(pad "G10" smd circle
			(at -1.199896 -3.599942 270)
			(size 0.3556 0.3556)
			(layers "F.Cu" "F.Mask" "F.Paste")
			(net "P1V15_STBY")
		)
		(pad "G11" smd circle
			(at -0.40005 -3.599942 270)
			(size 0.3556 0.3556)
			(layers "F.Cu" "F.Mask" "F.Paste")
			(net "P1V15_STBY")
		)
		(pad "G12" smd circle
			(at 0.40005 -3.599942 270)
			(size 0.3556 0.3556)
			(layers "F.Cu" "F.Mask" "F.Paste")
			(net "P1V15_STBY")
		)
		(pad "G13" smd circle
			(at 1.199896 -3.599942 270)
			(size 0.3556 0.3556)
			(layers "F.Cu" "F.Mask" "F.Paste")
			(net "P1V15_STBY")
		)
		(pad "G14" smd circle
			(at 1.999996 -3.599942 270)
			(size 0.3556 0.3556)
			(layers "F.Cu" "F.Mask" "F.Paste")
			(net "P1V15_STBY")
		)
		(pad "G15" smd circle
			(at 2.800096 -3.599942 270)
			(size 0.3556 0.3556)
			(layers "F.Cu" "F.Mask" "F.Paste")
			(net "P1V15_STBY")
		)
		(pad "G16" smd circle
			(at 3.599942 -3.599942 270)
			(size 0.3556 0.3556)
			(layers "F.Cu" "F.Mask" "F.Paste")
			(net "P3V3_STBY")
		)
		(pad "G17" smd circle
			(at 4.400042 -3.599942 270)
			(size 0.3556 0.3556)
			(layers "F.Cu" "F.Mask" "F.Paste")
			(net "P12V_A_PGOOD_R")
		)
		(pad "G18" smd circle
			(at 5.199888 -3.599942 270)
			(size 0.3556 0.3556)
			(layers "F.Cu" "F.Mask" "F.Paste")
			(net "Net_545")
		)
		(pad "G19" smd circle
			(at 5.999988 -3.599942 270)
			(size 0.3556 0.3556)
			(layers "F.Cu" "F.Mask" "F.Paste")
			(net "GND")
		)
		(pad "G20" smd circle
			(at 6.800088 -3.599942 270)
			(size 0.3556 0.3556)
			(layers "F.Cu" "F.Mask" "F.Paste")
			(net "TP_BMC0_LPC_LAD1")
		)
		(pad "G21" smd circle
			(at 7.599934 -3.599942 270)
			(size 0.3556 0.3556)
			(layers "F.Cu" "F.Mask" "F.Paste")
			(net "TP_BMC0_LPC_LAD0")
		)
		(pad "G22" smd circle
			(at 8.400034 -3.599942 270)
			(size 0.3556 0.3556)
			(layers "F.Cu" "F.Mask" "F.Paste")
			(net "LPCRST0_N")
		)
		(pad "H1" smd circle
			(at -8.400034 -2.800096 270)
			(size 0.3556 0.3556)
			(layers "F.Cu" "F.Mask" "F.Paste")
			(net "ADCVREFFN")
		)
		(pad "H2" smd circle
			(at -7.599934 -2.800096 270)
			(size 0.3556 0.3556)
			(layers "F.Cu" "F.Mask" "F.Paste")
			(net "ADCVREFFP")
		)
		(pad "H3" smd circle
			(at -6.800088 -2.800096 270)
			(size 0.3556 0.3556)
			(layers "F.Cu" "F.Mask" "F.Paste")
			(net "GND")
		)
		(pad "H4" smd circle
			(at -5.999988 -2.800096 270)
			(size 0.3556 0.3556)
			(layers "F.Cu" "F.Mask" "F.Paste")
			(net "GND")
		)
		(pad "H5" smd circle
			(at -5.199888 -2.800096 270)
			(size 0.3556 0.3556)
			(layers "F.Cu" "F.Mask" "F.Paste")
			(net "GND")
		)
		(pad "H6" smd circle
			(at -4.400042 -2.800096 270)
			(size 0.3556 0.3556)
			(layers "F.Cu" "F.Mask" "F.Paste")
			(net "GND")
		)
		(pad "H7" smd circle
			(at -3.599942 -2.800096 270)
			(size 0.3556 0.3556)
			(layers "F.Cu" "F.Mask" "F.Paste")
			(net "VPLLAV33")
		)
		(pad "H16" smd circle
			(at 3.599942 -2.800096 270)
			(size 0.3556 0.3556)
			(layers "F.Cu" "F.Mask" "F.Paste")
			(net "P1V15_STBY")
		)
		(pad "H17" smd circle
			(at 4.400042 -2.800096 270)
			(size 0.3556 0.3556)
			(layers "F.Cu" "F.Mask" "F.Paste")
			(net "P3V3_STBY")
		)
		(pad "H18" smd circle
			(at 5.199888 -2.800096 270)
			(size 0.3556 0.3556)
			(layers "F.Cu" "F.Mask" "F.Paste")
			(net "SCC_RMT_TYPE_0_R")
		)
		(pad "H19" smd circle
			(at 5.999988 -2.800096 270)
			(size 0.3556 0.3556)
			(layers "F.Cu" "F.Mask" "F.Paste")
			(net "DPB_MISC_ALERT_O_R")
		)
		(pad "H20" smd circle
			(at 6.800088 -2.800096 270)
			(size 0.3556 0.3556)
			(layers "F.Cu" "F.Mask" "F.Paste")
			(net "Net_544")
		)
		(pad "H21" smd circle
			(at 7.599934 -2.800096 270)
			(size 0.3556 0.3556)
			(layers "F.Cu" "F.Mask" "F.Paste")
			(net "M2_2_ALERT#_R")
		)
		(pad "H22" smd circle
			(at 8.400034 -2.800096 270)
			(size 0.3556 0.3556)
			(layers "F.Cu" "F.Mask" "F.Paste")
			(net "Net_543")
		)
		(pad "J1" smd circle
			(at -8.400034 -1.999996 270)
			(size 0.3556 0.3556)
			(layers "F.Cu" "F.Mask" "F.Paste")
			(net "ADCVREXT")
		)
		(pad "J2" smd circle
			(at -7.599934 -1.999996 270)
			(size 0.3556 0.3556)
			(layers "F.Cu" "F.Mask" "F.Paste")
			(net "Net_559")
		)
		(pad "J3" smd circle
			(at -6.800088 -1.999996 270)
			(size 0.3556 0.3556)
			(layers "F.Cu" "F.Mask" "F.Paste")
			(net "Net_558")
		)
		(pad "J4" smd circle
			(at -5.999988 -1.999996 270)
			(size 0.3556 0.3556)
			(layers "F.Cu" "F.Mask" "F.Paste")
			(net "Net_557")
		)
		(pad "J5" smd circle
			(at -5.199888 -1.999996 270)
			(size 0.3556 0.3556)
			(layers "F.Cu" "F.Mask" "F.Paste")
			(net "GND")
		)
		(pad "J6" smd circle
			(at -4.400042 -1.999996 270)
			(size 0.3556 0.3556)
			(layers "F.Cu" "F.Mask" "F.Paste")
			(net "ADCAV33")
		)
		(pad "J7" smd circle
			(at -3.599942 -1.999996 270)
			(size 0.3556 0.3556)
			(layers "F.Cu" "F.Mask" "F.Paste")
			(net "VPLLAV33")
		)
		(pad "J9" smd circle
			(at -1.999996 -1.999996 270)
			(size 0.3556 0.3556)
			(layers "F.Cu" "F.Mask" "F.Paste")
			(net "GND")
		)
		(pad "J10" smd circle
			(at -1.199896 -1.999996 270)
			(size 0.3556 0.3556)
			(layers "F.Cu" "F.Mask" "F.Paste")
			(net "GND")
		)
		(pad "J11" smd circle
			(at -0.40005 -1.999996 270)
			(size 0.3556 0.3556)
			(layers "F.Cu" "F.Mask" "F.Paste")
			(net "GND")
		)
		(pad "J12" smd circle
			(at 0.40005 -1.999996 270)
			(size 0.3556 0.3556)
			(layers "F.Cu" "F.Mask" "F.Paste")
			(net "GND")
		)
		(pad "J13" smd circle
			(at 1.199896 -1.999996 270)
			(size 0.3556 0.3556)
			(layers "F.Cu" "F.Mask" "F.Paste")
			(net "GND")
		)
		(pad "J14" smd circle
			(at 1.999996 -1.999996 270)
			(size 0.3556 0.3556)
			(layers "F.Cu" "F.Mask" "F.Paste")
			(net "GND")
		)
		(pad "J16" smd circle
			(at 3.599942 -1.999996 270)
			(size 0.3556 0.3556)
			(layers "F.Cu" "F.Mask" "F.Paste")
			(net "P1V15_STBY")
		)
		(pad "J17" smd circle
			(at 4.400042 -1.999996 270)
			(size 0.3556 0.3556)
			(layers "F.Cu" "F.Mask" "F.Paste")
			(net "P1V8_STBY")
		)
	)
)
